FILE_TYPE = MACRO_DRAWING;
SET COLOR_WIRE YELLOW;
SET COLOR_PROP MONO;
SET COLOR_DOT WHITE;
SET COLOR_ARC YELLOW;
SET COLOR_BODY GREEN;
SET COLOR_NOTE MONO;
SET PROP_DISPLAY VALUE;
SET PAGE_NUMBER P7;
FORCEADD INTEL_CORP_BPAGE..1
(4400 50);
FORCEPROP 1 LAST CDS_CON_LAST_MODIFIED Fri Jun 16 17:47:59 2017
J 0
(2975 375);
PAINT ORANGE (2975 375);
DISPLAY INVISIBLE (2975 375);
FORCEPROP 1 LAST CUSTOM_TXT_CDS <CURRENT_DESIGN_SHEET> OF <TOTAL_DESIGN_SHEETS>
J 0
(3900 75);
PAINT ORANGE (3900 75);
FORCEPROP 1 LAST CUSTOM_TXT_CDS <CON_LAST_MODIFIED>
J 0
(400 150);
PAINT ORANGE (400 150);
FORCEPROP 2 LAST CUSTOM_TXT_CDS <XR_PAGE_TITLE>
J 0
(-3490 5300);
DISPLAY 0.638298 (-3490 5300);
PAINT PINK (-3490 5300);
DISPLAY INVISIBLE (-3490 5300);
FORCEPROP 1 LAST SCH_TITLE SMBUS BLOCK DIAGRAM
J 0
(-3550 100);
DISPLAY 1.212766 (-3550 100);
PAINT ORANGE (-3550 100);
FORCEPROP 1 LAST COMMENT_BODY TRUE
J 0
(4412 62);
DISPLAY 0.468085 (4412 62);
PAINT GREEN (4412 62);
DISPLAY INVISIBLE (4412 62);
FORCEPROP 2 LAST PAGE_BORDER TRUE
J 0
(-3490 5300);
DISPLAY 0.638298 (-3490 5300);
PAINT PINK (-3490 5300);
DISPLAY INVISIBLE (-3490 5300);
FORCEPROP 2 LAST CDS_LIB mstr_symbols
J 0
(4400 50);
PAINT MONO (4400 50);
DISPLAY INVISIBLE (4400 50);
FORCEPROP 2 LAST CDS_XR_PAGE_TITLE CR-7 : @BASEBOARD_FAB2_LIB.BASEBOARD_FAB2(SCH_1):PAGE7
J 0
(-3490 5300);
DISPLAY 0.638298 (-3490 5300);
PAINT PINK (-3490 5300);
DISPLAY INVISIBLE (-3490 5300);
FORCENOTE
$CDS_IMAGE|TiogaPass_SYSTEM_Block_diagram_3_0314.jpg|7750|7750
(375 2250) 0;
DISPLAY LEFT (375 2250);
QUIT
